(kicad_pcb
	(version 20241229)
	(generator "pcbnew")
	(generator_version "9.0")
	(general
		(thickness 1.294)
		(legacy_teardrops no)
	)
	(paper "A3")
	(title_block
		(title "Kintex 410T devboard")
		(date "2024-04-03")
		(rev "1.1.2")
		(comment 9 "footprints 360-360 of 975")
	)
	(layers
		(0 "F.Cu" mixed)
		(4 "In1.Cu" power)
		(6 "In2.Cu" power)
		(8 "In3.Cu" mixed)
		(10 "In4.Cu" power)
		(12 "In5.Cu" mixed)
		(14 "In6.Cu" power)
		(16 "In7.Cu" mixed)
		(18 "In8.Cu" power)
		(2 "B.Cu" mixed)
		(9 "F.Adhes" user "F.Adhesive")
		(11 "B.Adhes" user "B.Adhesive")
		(13 "F.Paste" user)
		(15 "B.Paste" user)
		(5 "F.SilkS" user "F.Silkscreen")
		(7 "B.SilkS" user "B.Silkscreen")
		(1 "F.Mask" user)
		(3 "B.Mask" user)
		(17 "Dwgs.User" user "User.Drawings")
		(19 "Cmts.User" user "User.Comments")
		(21 "Eco1.User" user "User.Eco1")
		(23 "Eco2.User" user "User.Eco2")
		(25 "Edge.Cuts" user)
		(27 "Margin" user)
		(31 "F.CrtYd" user "F.Courtyard")
		(29 "B.CrtYd" user "B.Courtyard")
		(35 "F.Fab" user)
		(33 "B.Fab" user)
	)
	(footprint "antmicro-footprints:SW_DIP_SPSTx08_Slide_Copal_CVS-08xB_W5.9mm_P1mm"
		(layer "F.Cu")
		(at 257.2 74 90)
		(descr "SMD 8x-dip-switch SPST Copal_CVS-08xB, Slide, row spacing 5.9 mm (232 mils), body size  (see http://www.nidec-copal-electronics.com/e/catalog/switch/cvs.pdf)")
		(tags "SMD DIP Switch SPST Slide 5.9mm 232mil")
		(property "Reference" "SW2"
			(at -3.7 3.9 180)
			(layer "F.SilkS")
			(effects
				(font
					(size 0.7 0.7)
					(thickness 0.15)
				)
				(justify left bottom)
			)
		)
		(property "Value" "SW_CVS-08TB"
			(at -14.59 6.29 90)
			(layer "F.Fab")
			(effects
				(font
					(size 0.7 0.7)
					(thickness 0.15)
				)
				(justify left bottom)
			)
		)
		(property "Description" "DIP / SIP Switch, 8 Circuits, Slide, Surface Mount, SPST, 6 V, 100 mA"
			(at 0 0 90)
			(layer "F.Fab")
			(hide yes)
			(effects
				(font
					(size 1.27 1.27)
					(thickness 0.15)
				)
			)
		)
		(property "Author" "Antmicro"
			(at 331.2 -183.2 0)
			(layer "F.Fab")
			(hide yes)
			(effects
				(font
					(size 1 1)
					(thickness 0.15)
				)
			)
		)
		(property "License" "Apache-2.0"
			(at 331.2 -183.2 0)
			(layer "F.Fab")
			(hide yes)
			(effects
				(font
					(size 1 1)
					(thickness 0.15)
				)
			)
		)
		(property "MPN" "CVS-08TB"
			(at 331.2 -183.2 0)
			(layer "F.Fab")
			(hide yes)
			(effects
				(font
					(size 1 1)
					(thickness 0.15)
				)
			)
		)
		(property "Manufacturer" "Nidec Components"
			(at 331.2 -183.2 0)
			(layer "F.Fab")
			(hide yes)
			(effects
				(font
					(size 1 1)
					(thickness 0.15)
				)
			)
		)
		(sheetname "User GPIO + LED + button + DIP switch")
		(sheetfile "user-gpio.kicad_sch")
		(attr smd)
		(fp_line
			(start -1.561 -4.912)
			(end 1.56 -4.912)
			(stroke
				(width 0.15)
				(type solid)
			)
			(layer "F.SilkS")
		)
		(fp_line
			(start -1.561 4.91)
			(end 1.56 4.91)
			(stroke
				(width 0.15)
				(type solid)
			)
			(layer "F.SilkS")
		)
		(fp_circle
			(center -3.31 -4.2)
			(end -3.261 -4.2)
			(stroke
				(width 0.15)
				(type solid)
			)
			(fill yes)
			(layer "F.SilkS")
		)
		(fp_rect
			(start -3.601 -5)
			(end 3.598 4.998)
			(stroke
				(width 0.05)
				(type solid)
			)
			(fill no)
			(layer "F.CrtYd")
		)
		(fp_line
			(start 2.35 -4.5)
			(end 2.35 4.498)
			(stroke
				(width 0.15)
				(type solid)
			)
			(layer "F.Fab")
		)
		(fp_line
			(start -1.351 -4.5)
			(end 2.35 -4.5)
			(stroke
				(width 0.15)
				(type solid)
			)
			(layer "F.Fab")
		)
		(fp_line
			(start 0.998 -3.75)
			(end -1 -3.75)
			(stroke
				(width 0.15)
				(type solid)
			)
			(layer "F.Fab")
		)
		(fp_line
			(start -0.335 -3.75)
			(end -0.335 -3.25)
			(stroke
				(width 0.15)
				(type solid)
			)
			(layer "F.Fab")
		)
		(fp_line
			(start -1 -3.75)
			(end -1 -3.25)
			(stroke
				(width 0.15)
				(type solid)
			)
			(layer "F.Fab")
		)
		(fp_line
			(start -1 -3.65)
			(end -0.335 -3.65)
			(stroke
				(width 0.15)
				(type solid)
			)
			(layer "F.Fab")
		)
		(fp_line
			(start -1 -3.551)
			(end -0.335 -3.551)
			(stroke
				(width 0.15)
				(type solid)
			)
			(layer "F.Fab")
		)
		(fp_line
			(start -2.351 -3.5)
			(end -1.351 -4.5)
			(stroke
				(width 0.15)
				(type solid)
			)
			(layer "F.Fab")
		)
		(fp_line
			(start -1 -3.451)
			(end -0.335 -3.451)
			(stroke
				(width 0.15)
				(type solid)
			)
			(layer "F.Fab")
		)
		(fp_line
			(start -1 -3.351)
			(end -0.335 -3.351)
			(stroke
				(width 0.15)
				(type solid)
			)
			(layer "F.Fab")
		)
		(fp_line
			(start 0.998 -3.25)
			(end 0.998 -3.75)
			(stroke
				(width 0.15)
				(type solid)
			)
			(layer "F.Fab")
		)
		(fp_line
			(start -1 -3.25)
			(end 0.998 -3.25)
			(stroke
				(width 0.15)
				(type solid)
			)
			(layer "F.Fab")
		)
		(fp_line
			(start 0.998 -2.75)
			(end -1 -2.75)
			(stroke
				(width 0.15)
				(type solid)
			)
			(layer "F.Fab")
		)
		(fp_line
			(start -0.335 -2.75)
			(end -0.335 -2.25)
			(stroke
				(width 0.15)
				(type solid)
			)
			(layer "F.Fab")
		)
		(fp_line
			(start -1 -2.75)
			(end -1 -2.25)
			(stroke
				(width 0.15)
				(type solid)
			)
			(layer "F.Fab")
		)
		(fp_line
			(start -1 -2.65)
			(end -0.335 -2.65)
			(stroke
				(width 0.15)
				(type solid)
			)
			(layer "F.Fab")
		)
		(fp_line
			(start -1 -2.551)
			(end -0.335 -2.551)
			(stroke
				(width 0.15)
				(type solid)
			)
			(layer "F.Fab")
		)
		(fp_line
			(start -1 -2.452)
			(end -0.335 -2.452)
			(stroke
				(width 0.15)
				(type solid)
			)
			(layer "F.Fab")
		)
		(fp_line
			(start -1 -2.351)
			(end -0.335 -2.351)
			(stroke
				(width 0.15)
				(type solid)
			)
			(layer "F.Fab")
		)
		(fp_line
			(start 0.998 -2.25)
			(end 0.998 -2.75)
			(stroke
				(width 0.15)
				(type solid)
			)
			(layer "F.Fab")
		)
		(fp_line
			(start -1 -2.25)
			(end 0.998 -2.25)
			(stroke
				(width 0.15)
				(type solid)
			)
			(layer "F.Fab")
		)
		(fp_line
			(start 0.998 -1.75)
			(end -1 -1.75)
			(stroke
				(width 0.15)
				(type solid)
			)
			(layer "F.Fab")
		)
		(fp_line
			(start -0.335 -1.75)
			(end -0.335 -1.25)
			(stroke
				(width 0.15)
				(type solid)
			)
			(layer "F.Fab")
		)
		(fp_line
			(start -1 -1.75)
			(end -1 -1.25)
			(stroke
				(width 0.15)
				(type solid)
			)
			(layer "F.Fab")
		)
		(fp_line
			(start -1 -1.651)
			(end -0.335 -1.651)
			(stroke
				(width 0.15)
				(type solid)
			)
			(layer "F.Fab")
		)
		(fp_line
			(start -1 -1.551)
			(end -0.335 -1.551)
			(stroke
				(width 0.15)
				(type solid)
			)
			(layer "F.Fab")
		)
		(fp_line
			(start -1 -1.45)
			(end -0.335 -1.45)
			(stroke
				(width 0.15)
				(type solid)
			)
			(layer "F.Fab")
		)
		(fp_line
			(start -1 -1.351)
			(end -0.335 -1.351)
			(stroke
				(width 0.15)
				(type solid)
			)
			(layer "F.Fab")
		)
		(fp_line
			(start 0.998 -1.25)
			(end 0.998 -1.75)
			(stroke
				(width 0.15)
				(type solid)
			)
			(layer "F.Fab")
		)
		(fp_line
			(start -1 -1.25)
			(end 0.998 -1.25)
			(stroke
				(width 0.15)
				(type solid)
			)
			(layer "F.Fab")
		)
		(fp_line
			(start 0.998 -0.75)
			(end -1 -0.75)
			(stroke
				(width 0.15)
				(type solid)
			)
			(layer "F.Fab")
		)
		(fp_line
			(start -0.335 -0.75)
			(end -0.335 -0.25)
			(stroke
				(width 0.15)
				(type solid)
			)
			(layer "F.Fab")
		)
		(fp_line
			(start -1 -0.75)
			(end -1 -0.25)
			(stroke
				(width 0.15)
				(type solid)
			)
			(layer "F.Fab")
		)
		(fp_line
			(start -1 -0.652)
			(end -0.335 -0.652)
			(stroke
				(width 0.15)
				(type solid)
			)
			(layer "F.Fab")
		)
		(fp_line
			(start -1 -0.552)
			(end -0.335 -0.552)
			(stroke
				(width 0.15)
				(type solid)
			)
			(layer "F.Fab")
		)
		(fp_line
			(start -1 -0.452)
			(end -0.335 -0.452)
			(stroke
				(width 0.15)
				(type solid)
			)
			(layer "F.Fab")
		)
		(fp_line
			(start -1 -0.351)
			(end -0.335 -0.351)
			(stroke
				(width 0.15)
				(type solid)
			)
			(layer "F.Fab")
		)
		(fp_line
			(start 0.998 -0.25)
			(end 0.998 -0.75)
			(stroke
				(width 0.15)
				(type solid)
			)
			(layer "F.Fab")
		)
		(fp_line
			(start -1 -0.25)
			(end 0.998 -0.25)
			(stroke
				(width 0.15)
				(type solid)
			)
			(layer "F.Fab")
		)
		(fp_line
			(start 0.998 0.248)
			(end -1 0.248)
			(stroke
				(width 0.15)
				(type solid)
			)
			(layer "F.Fab")
		)
		(fp_line
			(start -0.335 0.248)
			(end -0.335 0.748)
			(stroke
				(width 0.15)
				(type solid)
			)
			(layer "F.Fab")
		)
		(fp_line
			(start -1 0.248)
			(end -1 0.748)
			(stroke
				(width 0.15)
				(type solid)
			)
			(layer "F.Fab")
		)
		(fp_line
			(start -1 0.349)
			(end -0.335 0.349)
			(stroke
				(width 0.15)
				(type solid)
			)
			(layer "F.Fab")
		)
		(fp_line
			(start -1 0.45)
			(end -0.335 0.45)
			(stroke
				(width 0.15)
				(type solid)
			)
			(layer "F.Fab")
		)
		(fp_line
			(start -1 0.55)
			(end -0.335 0.55)
			(stroke
				(width 0.15)
				(type solid)
			)
			(layer "F.Fab")
		)
		(fp_line
			(start -1 0.65)
			(end -0.335 0.65)
			(stroke
				(width 0.15)
				(type solid)
			)
			(layer "F.Fab")
		)
		(fp_line
			(start 0.998 0.748)
			(end 0.998 0.248)
			(stroke
				(width 0.15)
				(type solid)
			)
			(layer "F.Fab")
		)
		(fp_line
			(start -1 0.748)
			(end 0.998 0.748)
			(stroke
				(width 0.15)
				(type solid)
			)
			(layer "F.Fab")
		)
		(fp_line
			(start -1 0.748)
			(end -0.335 0.748)
			(stroke
				(width 0.15)
				(type solid)
			)
			(layer "F.Fab")
		)
		(fp_line
			(start 0.998 1.249)
			(end -1 1.249)
			(stroke
				(width 0.15)
				(type solid)
			)
			(layer "F.Fab")
		)
		(fp_line
			(start -0.335 1.249)
			(end -0.335 1.749)
			(stroke
				(width 0.15)
				(type solid)
			)
			(layer "F.Fab")
		)
		(fp_line
			(start -1 1.249)
			(end -1 1.749)
			(stroke
				(width 0.15)
				(type solid)
			)
			(layer "F.Fab")
		)
		(fp_line
			(start -1 1.35)
			(end -0.335 1.35)
			(stroke
				(width 0.15)
				(type solid)
			)
			(layer "F.Fab")
		)
		(fp_line
			(start -1 1.449)
			(end -0.335 1.449)
			(stroke
				(width 0.15)
				(type solid)
			)
			(layer "F.Fab")
		)
		(fp_line
			(start -1 1.55)
			(end -0.335 1.55)
			(stroke
				(width 0.15)
				(type solid)
			)
			(layer "F.Fab")
		)
		(fp_line
			(start -1 1.648)
			(end -0.335 1.648)
			(stroke
				(width 0.15)
				(type solid)
			)
			(layer "F.Fab")
		)
		(fp_line
			(start 0.998 1.749)
			(end 0.998 1.249)
			(stroke
				(width 0.15)
				(type solid)
			)
			(layer "F.Fab")
		)
		(fp_line
			(start -1 1.749)
			(end 0.998 1.749)
			(stroke
				(width 0.15)
				(type solid)
			)
			(layer "F.Fab")
		)
		(fp_line
			(start -1 1.749)
			(end -0.335 1.749)
			(stroke
				(width 0.15)
				(type solid)
			)
			(layer "F.Fab")
		)
		(fp_line
			(start 0.998 2.249)
			(end -1 2.249)
			(stroke
				(width 0.15)
				(type solid)
			)
			(layer "F.Fab")
		)
		(fp_line
			(start -0.335 2.249)
			(end -0.335 2.749)
			(stroke
				(width 0.15)
				(type solid)
			)
			(layer "F.Fab")
		)
		(fp_line
			(start -1 2.249)
			(end -1 2.749)
			(stroke
				(width 0.15)
				(type solid)
			)
			(layer "F.Fab")
		)
		(fp_line
			(start -1 2.35)
			(end -0.335 2.35)
			(stroke
				(width 0.15)
				(type solid)
			)
			(layer "F.Fab")
		)
		(fp_line
			(start -1 2.45)
			(end -0.335 2.45)
			(stroke
				(width 0.15)
				(type solid)
			)
			(layer "F.Fab")
		)
		(fp_line
			(start -1 2.548)
			(end -0.335 2.548)
			(stroke
				(width 0.15)
				(type solid)
			)
			(layer "F.Fab")
		)
		(fp_line
			(start -1 2.648)
			(end -0.335 2.648)
			(stroke
				(width 0.15)
				(type solid)
			)
			(layer "F.Fab")
		)
		(fp_line
			(start 0.998 2.749)
			(end 0.998 2.249)
			(stroke
				(width 0.15)
				(type solid)
			)
			(layer "F.Fab")
		)
		(fp_line
			(start -1 2.749)
			(end 0.998 2.749)
			(stroke
				(width 0.15)
				(type solid)
			)
			(layer "F.Fab")
		)
		(fp_line
			(start -1 2.749)
			(end -0.335 2.749)
			(stroke
				(width 0.15)
				(type solid)
			)
			(layer "F.Fab")
		)
		(fp_line
			(start 0.998 3.249)
			(end -1 3.249)
			(stroke
				(width 0.15)
				(type solid)
			)
			(layer "F.Fab")
		)
		(fp_line
			(start -0.335 3.249)
			(end -0.335 3.749)
			(stroke
				(width 0.15)
				(type solid)
			)
			(layer "F.Fab")
		)
		(fp_line
			(start -1 3.249)
			(end -1 3.749)
			(stroke
				(width 0.15)
				(type solid)
			)
			(layer "F.Fab")
		)
		(fp_line
			(start -1 3.35)
			(end -0.335 3.35)
			(stroke
				(width 0.15)
				(type solid)
			)
			(layer "F.Fab")
		)
		(fp_line
			(start -1 3.45)
			(end -0.335 3.45)
			(stroke
				(width 0.15)
				(type solid)
			)
			(layer "F.Fab")
		)
		(fp_line
			(start -1 3.548)
			(end -0.335 3.548)
			(stroke
				(width 0.15)
				(type solid)
			)
			(layer "F.Fab")
		)
		(fp_line
			(start -1 3.648)
			(end -0.335 3.648)
			(stroke
				(width 0.15)
				(type solid)
			)
			(layer "F.Fab")
		)
		(fp_line
			(start 0.998 3.749)
			(end 0.998 3.249)
			(stroke
				(width 0.15)
				(type solid)
			)
			(layer "F.Fab")
		)
		(fp_line
			(start -1 3.749)
			(end 0.998 3.749)
			(stroke
				(width 0.15)
				(type solid)
			)
			(layer "F.Fab")
		)
		(fp_line
			(start -1 3.749)
			(end -0.335 3.749)
			(stroke
				(width 0.15)
				(type solid)
			)
			(layer "F.Fab")
		)
		(fp_line
			(start 2.35 4.498)
			(end -2.351 4.498)
			(stroke
				(width 0.15)
				(type solid)
			)
			(layer "F.Fab")
		)
		(fp_line
			(start -2.351 4.498)
			(end -2.351 -3.5)
			(stroke
				(width 0.15)
				(type solid)
			)
			(layer "F.Fab")
		)
		(fp_text user "on"
			(at -1.56 0.69 180)
			(layer "F.Fab")
			(effects
				(font
					(size 0.7 0.7)
					(thickness 0.15)
				)
				(justify left bottom)
			)
		)
		(pad "1" smd rect
			(at -2.952 -3.5 90)
			(size 1.2 0.5)
			(layers "F.Cu" "F.Mask" "F.Paste")
			(net 1311 "/USER_IO.DIP_SW0")
			(pinfunction "1")
			(pintype "passive")
		)
		(pad "2" smd rect
			(at -2.952 -2.5 90)
			(size 1.2 0.5)
			(layers "F.Cu" "F.Mask" "F.Paste")
			(net 1310 "/USER_IO.DIP_SW1")
			(pinfunction "2")
			(pintype "passive")
		)
		(pad "3" smd rect
			(at -2.952 -1.5 90)
			(size 1.2 0.5)
			(layers "F.Cu" "F.Mask" "F.Paste")
			(net 1309 "/USER_IO.DIP_SW2")
			(pinfunction "3")
			(pintype "passive")
		)
		(pad "4" smd rect
			(at -2.952 -0.5 90)
			(size 1.2 0.5)
			(layers "F.Cu" "F.Mask" "F.Paste")
			(net 1308 "/USER_IO.DIP_SW3")
			(pinfunction "4")
			(pintype "passive")
		)
		(pad "5" smd rect
			(at -2.952 0.498 90)
			(size 1.2 0.5)
			(layers "F.Cu" "F.Mask" "F.Paste")
			(net 1324 "/USER_IO.DIP_SW4")
			(pinfunction "5")
			(pintype "passive")
		)
		(pad "6" smd rect
			(at -2.952 1.499 90)
			(size 1.2 0.5)
			(layers "F.Cu" "F.Mask" "F.Paste")
			(net 1322 "/USER_IO.DIP_SW5")
			(pinfunction "6")
			(pintype "passive")
		)
		(pad "7" smd rect
			(at -2.952 2.499 90)
			(size 1.2 0.5)
			(layers "F.Cu" "F.Mask" "F.Paste")
			(net 1320 "/USER_IO.DIP_SW6")
			(pinfunction "7")
			(pintype "passive")
		)
		(pad "8" smd rect
			(at -2.952 3.499 90)
			(size 1.2 0.5)
			(layers "F.Cu" "F.Mask" "F.Paste")
			(net 1318 "/USER_IO.DIP_SW7")
			(pinfunction "8")
			(pintype "passive")
		)
		(pad "9" smd rect
			(at 2.95 3.499 90)
			(size 1.2 0.5)
			(layers "F.Cu" "F.Mask" "F.Paste")
			(net 1 "GND")
			(pinfunction "9")
			(pintype "passive")
		)
		(pad "10" smd rect
			(at 2.95 2.499 90)
			(size 1.2 0.5)
			(layers "F.Cu" "F.Mask" "F.Paste")
			(net 1 "GND")
			(pinfunction "10")
			(pintype "passive")
		)
		(pad "11" smd rect
			(at 2.95 1.499 90)
			(size 1.2 0.5)
			(layers "F.Cu" "F.Mask" "F.Paste")
			(net 1 "GND")
			(pinfunction "11")
			(pintype "passive")
		)
		(pad "12" smd rect
			(at 2.95 0.498 90)
			(size 1.2 0.5)
			(layers "F.Cu" "F.Mask" "F.Paste")
			(net 1 "GND")
			(pinfunction "12")
			(pintype "passive")
		)
		(pad "13" smd rect
			(at 2.95 -0.5 90)
			(size 1.2 0.5)
			(layers "F.Cu" "F.Mask" "F.Paste")
			(net 1 "GND")
			(pinfunction "13")
			(pintype "passive")
		)
		(pad "14" smd rect
			(at 2.95 -1.5 90)
			(size 1.2 0.5)
			(layers "F.Cu" "F.Mask" "F.Paste")
			(net 1 "GND")
			(pinfunction "14")
			(pintype "passive")
		)
		(pad "15" smd rect
			(at 2.95 -2.5 90)
			(size 1.2 0.5)
			(layers "F.Cu" "F.Mask" "F.Paste")
			(net 1 "GND")
			(pinfunction "15")
			(pintype "passive")
		)
		(pad "16" smd rect
			(at 2.95 -3.5 90)
			(size 1.2 0.5)
			(layers "F.Cu" "F.Mask" "F.Paste")
			(net 1 "GND")
			(pinfunction "16")
			(pintype "passive")
		)
		(pad "17" smd rect
			(at -2.15 -4.5 90)
			(size 0.7 0.7)
			(layers "F.Cu" "F.Mask" "F.Paste")
			(net 1 "GND")
			(pinfunction "17")
			(pintype "power_in")
		)
		(pad "17" smd rect
			(at -2.15 4.498 90)
			(size 0.7 0.7)
			(layers "F.Cu" "F.Mask" "F.Paste")
			(net 1 "GND")
			(pinfunction "17")
			(pintype "power_in")
		)
		(pad "17" smd rect
			(at 2.148 -4.5 90)
			(size 0.7 0.7)
			(layers "F.Cu" "F.Mask" "F.Paste")
			(net 1 "GND")
			(pinfunction "17")
			(pintype "power_in")
		)
		(pad "17" smd rect
			(at 2.148 4.498 90)
			(size 0.7 0.7)
			(layers "F.Cu" "F.Mask" "F.Paste")
			(net 1 "GND")
			(pinfunction "17")
			(pintype "power_in")
		)
	)
)
